(kicad_pcb
	(version 20260206)
	(generator "pcbnew")
	(generator_version "10.0")
	(general
		(thickness 1.6)
		(legacy_teardrops no)
	)
	(paper "A4")
	(title_block
		(title "01162023_DA0F0TEBIF0_F0T_Expander_BD_F_brd_V02_OCP.brd")
		(comment 1 "Grand Teton / footprints 402-409 of 9728")
	)
	(layers
		(0 "F.Cu" signal "TOP")
		(4 "In1.Cu" signal "GND")
		(6 "In2.Cu" signal "VCC")
		(8 "In3.Cu" signal "VCC1")
		(10 "In4.Cu" signal "GND1")
		(12 "In5.Cu" signal "IN1")
		(14 "In6.Cu" signal "GND2")
		(16 "In7.Cu" signal "IN2")
		(18 "In8.Cu" signal "GND3")
		(20 "In9.Cu" signal "IN3")
		(22 "In10.Cu" signal "GND4")
		(24 "In11.Cu" signal "IN4")
		(26 "In12.Cu" signal "GND5")
		(28 "In13.Cu" signal "IN5")
		(30 "In14.Cu" signal "GND6")
		(32 "In15.Cu" signal "IN6")
		(34 "In16.Cu" signal "GND7")
		(2 "B.Cu" signal "BOTTOM")
		(9 "F.Adhes" user "F.Adhesive")
		(11 "B.Adhes" user "B.Adhesive")
		(13 "F.Paste" user "Package Geometry/Pastemask Top")
		(15 "B.Paste" user "Package Geometry/Pastemask Bottom")
		(5 "F.SilkS" user "Ref Des/Silkscreen Top")
		(7 "B.SilkS" user "Ref Des/Silkscreen Bottom")
		(1 "F.Mask" user "Board Geometry/Soldermask Top")
		(3 "B.Mask" user "Board Geometry/Soldermask Bottom")
		(17 "Dwgs.User" user "User.Drawings")
		(19 "Cmts.User" user "User.Comments")
		(21 "Eco1.User" user "User.Eco1")
		(23 "Eco2.User" user "User.Eco2")
		(25 "Edge.Cuts" user "Board Geometry/Outline")
		(27 "Margin" user)
		(31 "F.CrtYd" user "Package Geometry/Place Bound Top")
		(29 "B.CrtYd" user "Package Geometry/Place Bound Bottom")
		(35 "F.Fab" user "Ref Des/Assembly Top")
		(33 "B.Fab" user "Ref Des/Assembly Bottom")
	)
	(footprint ""
		(layer "F.Cu")
		(at 112.67186 -130.946144)
		(property "Reference" "PC299"
			(at 0 0 0)
			(layer "F.SilkS")
			(hide yes)
			(effects
				(font
					(size 1.27 1.27)
				)
			)
		)
		(property "Value" ""
			(at 0 0 0)
			(layer "F.Fab")
			(effects
				(font
					(size 1.27 1.27)
				)
			)
		)
		(duplicate_pad_numbers_are_jumpers no)
		(fp_line
			(start -1.524 -0.762)
			(end 1.524 -0.762)
			(stroke
				(width 0.1524)
				(type default)
			)
			(layer "F.SilkS")
		)
		(fp_line
			(start -1.524 0.762)
			(end -1.524 -0.762)
			(stroke
				(width 0.1524)
				(type default)
			)
			(layer "F.SilkS")
		)
		(fp_line
			(start 1.524 -0.762)
			(end 1.524 0.762)
			(stroke
				(width 0.1524)
				(type default)
			)
			(layer "F.SilkS")
		)
		(fp_line
			(start 1.524 0.762)
			(end -1.524 0.762)
			(stroke
				(width 0.1524)
				(type default)
			)
			(layer "F.SilkS")
		)
		(fp_line
			(start -1.1049 -0.724916)
			(end -1.1049 0.724916)
			(stroke
				(width 0.1)
				(type default)
			)
			(layer "F.Fab")
		)
		(fp_line
			(start -1.1049 0.724916)
			(end 1.1049 0.724916)
			(stroke
				(width 0.1)
				(type default)
			)
			(layer "F.Fab")
		)
		(fp_line
			(start 1.1049 -0.724916)
			(end -1.1049 -0.724916)
			(stroke
				(width 0.1)
				(type default)
			)
			(layer "F.Fab")
		)
		(fp_line
			(start 1.1049 0.724916)
			(end 1.1049 -0.724916)
			(stroke
				(width 0.1)
				(type default)
			)
			(layer "F.Fab")
		)
		(pad "1" smd rect
			(at -0.889 0 180)
			(size 1.016 1.27)
			(layers "F.Cu" "F.Mask" "F.Paste")
			(net "GND")
		)
		(pad "2" smd rect
			(at 0.889 0 180)
			(size 1.016 1.27)
			(layers "F.Cu" "F.Mask" "F.Paste")
			(net "P3V3_AUX")
		)
	)
	(footprint ""
		(layer "F.Cu")
		(at 30.081982 -286.590232 180)
		(property "Reference" "C3061"
			(at 0 0 180)
			(layer "F.SilkS")
			(hide yes)
			(effects
				(font
					(size 1.27 1.27)
				)
			)
		)
		(property "Value" ""
			(at 0 0 180)
			(layer "F.Fab")
			(effects
				(font
					(size 1.27 1.27)
				)
			)
		)
		(duplicate_pad_numbers_are_jumpers no)
		(fp_line
			(start 1.2954 0.5842)
			(end -1.2954 0.5842)
			(stroke
				(width 0.1524)
				(type default)
			)
			(layer "F.SilkS")
		)
		(fp_line
			(start 1.2954 -0.5842)
			(end 1.2954 0.5842)
			(stroke
				(width 0.1524)
				(type default)
			)
			(layer "F.SilkS")
		)
		(fp_line
			(start -1.2954 0.5842)
			(end -1.2954 -0.5842)
			(stroke
				(width 0.1524)
				(type default)
			)
			(layer "F.SilkS")
		)
		(fp_line
			(start -1.2954 -0.5842)
			(end 1.2954 -0.5842)
			(stroke
				(width 0.1524)
				(type default)
			)
			(layer "F.SilkS")
		)
		(fp_line
			(start 1.1938 0.4064)
			(end 0.8636 0.4064)
			(stroke
				(width 0.1)
				(type default)
			)
			(layer "F.Fab")
		)
		(fp_line
			(start 1.1938 -0.4064)
			(end 1.1938 0.4064)
			(stroke
				(width 0.1)
				(type default)
			)
			(layer "F.Fab")
		)
		(fp_line
			(start 0.8636 0.4572)
			(end -0.8636 0.4572)
			(stroke
				(width 0.1)
				(type default)
			)
			(layer "F.Fab")
		)
		(fp_line
			(start 0.8636 0.4064)
			(end 0.8636 0.4572)
			(stroke
				(width 0.1)
				(type default)
			)
			(layer "F.Fab")
		)
		(fp_line
			(start 0.8636 -0.4064)
			(end 1.1938 -0.4064)
			(stroke
				(width 0.1)
				(type default)
			)
			(layer "F.Fab")
		)
		(fp_line
			(start 0.8636 -0.4572)
			(end 0.8636 -0.4064)
			(stroke
				(width 0.1)
				(type default)
			)
			(layer "F.Fab")
		)
		(fp_line
			(start -0.8636 0.4572)
			(end -0.8636 0.4064)
			(stroke
				(width 0.1)
				(type default)
			)
			(layer "F.Fab")
		)
		(fp_line
			(start -0.8636 0.4064)
			(end -1.1938 0.4064)
			(stroke
				(width 0.1)
				(type default)
			)
			(layer "F.Fab")
		)
		(fp_line
			(start -0.8636 -0.4064)
			(end -0.8636 -0.4572)
			(stroke
				(width 0.1)
				(type default)
			)
			(layer "F.Fab")
		)
		(fp_line
			(start -0.8636 -0.4572)
			(end 0.8636 -0.4572)
			(stroke
				(width 0.1)
				(type default)
			)
			(layer "F.Fab")
		)
		(fp_line
			(start -1.1938 0.4064)
			(end -1.1938 -0.4064)
			(stroke
				(width 0.1)
				(type default)
			)
			(layer "F.Fab")
		)
		(fp_line
			(start -1.1938 -0.4064)
			(end -0.8636 -0.4064)
			(stroke
				(width 0.1)
				(type default)
			)
			(layer "F.Fab")
		)
		(pad "1" smd rect
			(at -0.7366 0 90)
			(size 0.7112 0.8128)
			(layers "F.Cu" "F.Mask" "F.Paste")
			(net "PCEPLL6_VDDA18_PEX0_R")
		)
		(pad "2" smd rect
			(at 0.7366 0 90)
			(size 0.7112 0.8128)
			(layers "F.Cu" "F.Mask" "F.Paste")
			(net "GND")
		)
	)
	(footprint ""
		(layer "F.Cu")
		(at 369.555776 -152.71115 90)
		(property "Reference" "R751"
			(at 0 0 90)
			(layer "F.SilkS")
			(hide yes)
			(effects
				(font
					(size 1.27 1.27)
				)
			)
		)
		(property "Value" ""
			(at 0 0 90)
			(layer "F.Fab")
			(effects
				(font
					(size 1.27 1.27)
				)
			)
		)
		(duplicate_pad_numbers_are_jumpers no)
		(fp_line
			(start 0.7874 -0.4064)
			(end 0.7874 0.4064)
			(stroke
				(width 0.1524)
				(type default)
			)
			(layer "F.SilkS")
		)
		(fp_line
			(start -0.7874 -0.4064)
			(end 0.7874 -0.4064)
			(stroke
				(width 0.1524)
				(type default)
			)
			(layer "F.SilkS")
		)
		(fp_line
			(start 0.7874 0.4064)
			(end -0.7874 0.4064)
			(stroke
				(width 0.1524)
				(type default)
			)
			(layer "F.SilkS")
		)
		(fp_line
			(start -0.7874 0.4064)
			(end -0.7874 -0.4064)
			(stroke
				(width 0.1524)
				(type default)
			)
			(layer "F.SilkS")
		)
		(fp_line
			(start -0.12065 -0.305054)
			(end -0.12065 -0.2794)
			(stroke
				(width 0.1)
				(type default)
			)
			(layer "F.Fab")
		)
		(fp_line
			(start -0.67945 -0.305054)
			(end -0.12065 -0.305054)
			(stroke
				(width 0.1)
				(type default)
			)
			(layer "F.Fab")
		)
		(fp_line
			(start 0.67945 -0.3048)
			(end 0.67945 0.3048)
			(stroke
				(width 0.1)
				(type default)
			)
			(layer "F.Fab")
		)
		(fp_line
			(start 0.12065 -0.3048)
			(end 0.67945 -0.3048)
			(stroke
				(width 0.1)
				(type default)
			)
			(layer "F.Fab")
		)
		(fp_line
			(start 0.12065 -0.2794)
			(end 0.12065 -0.3048)
			(stroke
				(width 0.1)
				(type default)
			)
			(layer "F.Fab")
		)
		(fp_line
			(start -0.12065 -0.2794)
			(end 0.12065 -0.2794)
			(stroke
				(width 0.1)
				(type default)
			)
			(layer "F.Fab")
		)
		(fp_line
			(start 0.120396 0.2794)
			(end -0.12065 0.2794)
			(stroke
				(width 0.1)
				(type default)
			)
			(layer "F.Fab")
		)
		(fp_line
			(start -0.12065 0.2794)
			(end -0.12065 0.3048)
			(stroke
				(width 0.1)
				(type default)
			)
			(layer "F.Fab")
		)
		(fp_line
			(start 0.67945 0.3048)
			(end 0.120396 0.3048)
			(stroke
				(width 0.1)
				(type default)
			)
			(layer "F.Fab")
		)
		(fp_line
			(start 0.120396 0.3048)
			(end 0.120396 0.2794)
			(stroke
				(width 0.1)
				(type default)
			)
			(layer "F.Fab")
		)
		(fp_line
			(start -0.12065 0.3048)
			(end -0.67945 0.3048)
			(stroke
				(width 0.1)
				(type default)
			)
			(layer "F.Fab")
		)
		(fp_line
			(start -0.67945 0.3048)
			(end -0.67945 -0.305054)
			(stroke
				(width 0.1)
				(type default)
			)
			(layer "F.Fab")
		)
		(pad "1" smd circle
			(at -0.40005 0 90)
			(size 0 0)
			(layers "F.Cu" "F.Mask" "F.Paste")
			(net "NIC6_ADC_A1")
		)
		(pad "2" smd circle
			(at 0.40005 0 90)
			(size 0 0)
			(layers "F.Cu" "F.Mask" "F.Paste")
			(net "GND")
		)
	)
	(footprint ""
		(layer "F.Cu")
		(at 17.006316 -305.19751)
		(property "Reference" "PJ10"
			(at 1.504696 -0.114808 0)
			(unlocked yes)
			(layer "F.SilkS")
			(effects
				(font
					(size 0.7874 0.5842)
					(thickness 0.1524)
				)
				(justify left)
			)
		)
		(property "Value" ""
			(at 0 0 0)
			(layer "F.Fab")
			(effects
				(font
					(size 1.27 1.27)
				)
			)
		)
		(duplicate_pad_numbers_are_jumpers no)
		(pad "1" smd circle
			(at -0.40005 0 90)
			(size 0 0)
			(layers "F.Cu" "F.Mask" "F.Paste")
			(net "SH_P1V25_PEX0_FB_N")
		)
		(pad "2" smd rect
			(at 0.40005 0 180)
			(size 0.4572 0.508)
			(layers "F.Cu" "F.Mask" "F.Paste")
			(net "GND")
		)
		(zone
			(layer "F.Cu")
			(hatch none 0.5)
			(connect_pads
				(clearance 0)
			)
			(min_thickness 0.25)
			(keepout
				(tracks allowed)
				(vias not_allowed)
				(pads allowed)
				(copperpour not_allowed)
				(footprints allowed)
			)
			(placement
				(enabled no)
				(sheetname "")
			)
			(fill
				(thermal_gap 0.5)
				(thermal_bridge_width 0.5)
				(island_removal_mode 0)
			)
			(polygon
				(pts
					(xy 16.320516 -304.89271) (xy 17.692116 -304.89271) (xy 17.692116 -305.50231) (xy 16.320516 -305.50231)
				)
			)
		)
	)
	(footprint ""
		(layer "F.Cu")
		(at 460.611982 -109.626654 180)
		(property "Reference" "R962"
			(at 0 0 180)
			(layer "F.SilkS")
			(hide yes)
			(effects
				(font
					(size 1.27 1.27)
				)
			)
		)
		(property "Value" ""
			(at 0 0 180)
			(layer "F.Fab")
			(effects
				(font
					(size 1.27 1.27)
				)
			)
		)
		(duplicate_pad_numbers_are_jumpers no)
		(fp_line
			(start 0.7874 0.4064)
			(end -0.7874 0.4064)
			(stroke
				(width 0.1524)
				(type default)
			)
			(layer "F.SilkS")
		)
		(fp_line
			(start 0.7874 -0.4064)
			(end 0.7874 0.4064)
			(stroke
				(width 0.1524)
				(type default)
			)
			(layer "F.SilkS")
		)
		(fp_line
			(start -0.7874 0.4064)
			(end -0.7874 -0.4064)
			(stroke
				(width 0.1524)
				(type default)
			)
			(layer "F.SilkS")
		)
		(fp_line
			(start -0.7874 -0.4064)
			(end 0.7874 -0.4064)
			(stroke
				(width 0.1524)
				(type default)
			)
			(layer "F.SilkS")
		)
		(fp_line
			(start 0.67945 0.3048)
			(end 0.120396 0.3048)
			(stroke
				(width 0.1)
				(type default)
			)
			(layer "F.Fab")
		)
		(fp_line
			(start 0.67945 -0.3048)
			(end 0.67945 0.3048)
			(stroke
				(width 0.1)
				(type default)
			)
			(layer "F.Fab")
		)
		(fp_line
			(start 0.12065 -0.2794)
			(end 0.12065 -0.3048)
			(stroke
				(width 0.1)
				(type default)
			)
			(layer "F.Fab")
		)
		(fp_line
			(start 0.12065 -0.3048)
			(end 0.67945 -0.3048)
			(stroke
				(width 0.1)
				(type default)
			)
			(layer "F.Fab")
		)
		(fp_line
			(start 0.120396 0.3048)
			(end 0.120396 0.2794)
			(stroke
				(width 0.1)
				(type default)
			)
			(layer "F.Fab")
		)
		(fp_line
			(start 0.120396 0.2794)
			(end -0.12065 0.2794)
			(stroke
				(width 0.1)
				(type default)
			)
			(layer "F.Fab")
		)
		(fp_line
			(start -0.12065 0.3048)
			(end -0.67945 0.3048)
			(stroke
				(width 0.1)
				(type default)
			)
			(layer "F.Fab")
		)
		(fp_line
			(start -0.12065 0.2794)
			(end -0.12065 0.3048)
			(stroke
				(width 0.1)
				(type default)
			)
			(layer "F.Fab")
		)
		(fp_line
			(start -0.12065 -0.2794)
			(end 0.12065 -0.2794)
			(stroke
				(width 0.1)
				(type default)
			)
			(layer "F.Fab")
		)
		(fp_line
			(start -0.12065 -0.305054)
			(end -0.12065 -0.2794)
			(stroke
				(width 0.1)
				(type default)
			)
			(layer "F.Fab")
		)
		(fp_line
			(start -0.67945 0.3048)
			(end -0.67945 -0.305054)
			(stroke
				(width 0.1)
				(type default)
			)
			(layer "F.Fab")
		)
		(fp_line
			(start -0.67945 -0.305054)
			(end -0.12065 -0.305054)
			(stroke
				(width 0.1)
				(type default)
			)
			(layer "F.Fab")
		)
		(pad "1" smd circle
			(at -0.40005 0 180)
			(size 0 0)
			(layers "F.Cu" "F.Mask" "F.Paste")
			(net "GND")
		)
		(pad "2" smd circle
			(at 0.40005 0 180)
			(size 0 0)
			(layers "F.Cu" "F.Mask" "F.Paste")
			(net "P12V_NIC7_CO_EN")
		)
	)
	(footprint ""
		(layer "F.Cu")
		(at 392.092434 -28.225242 180)
		(property "Reference" "C713"
			(at 0 0 180)
			(layer "F.SilkS")
			(hide yes)
			(effects
				(font
					(size 1.27 1.27)
				)
			)
		)
		(property "Value" ""
			(at 0 0 180)
			(layer "F.Fab")
			(effects
				(font
					(size 1.27 1.27)
				)
			)
		)
		(duplicate_pad_numbers_are_jumpers no)
		(fp_line
			(start 0.299974 0.150114)
			(end -0.299974 0.150114)
			(stroke
				(width 0.1)
				(type default)
			)
			(layer "F.Fab")
		)
		(fp_line
			(start 0.299974 -0.150114)
			(end 0.299974 0.150114)
			(stroke
				(width 0.1)
				(type default)
			)
			(layer "F.Fab")
		)
		(fp_line
			(start -0.299974 0.150114)
			(end -0.299974 -0.150114)
			(stroke
				(width 0.1)
				(type default)
			)
			(layer "F.Fab")
		)
		(fp_line
			(start -0.299974 -0.150114)
			(end 0.299974 -0.150114)
			(stroke
				(width 0.1)
				(type default)
			)
			(layer "F.Fab")
		)
		(pad "1" smd rect
			(at -0.2667 0 180)
			(size 0.3048 0.381)
			(layers "F.Cu" "F.Mask" "F.Paste")
			(net "P5E_PEX3_STN2_TX_DN<40>")
		)
		(pad "2" smd rect
			(at 0.2667 0 180)
			(size 0.3048 0.381)
			(layers "F.Cu" "F.Mask" "F.Paste")
			(net "P5E_PEX3_STN2_TX_C_DN<40>")
		)
	)
	(footprint ""
		(layer "F.Cu")
		(at 278.325326 -42.849038 180)
		(property "Reference" "R612"
			(at 0 0 180)
			(layer "F.SilkS")
			(hide yes)
			(effects
				(font
					(size 1.27 1.27)
				)
			)
		)
		(property "Value" ""
			(at 0 0 180)
			(layer "F.Fab")
			(effects
				(font
					(size 1.27 1.27)
				)
			)
		)
		(duplicate_pad_numbers_are_jumpers no)
		(fp_line
			(start 0.7874 0.4064)
			(end -0.7874 0.4064)
			(stroke
				(width 0.1524)
				(type default)
			)
			(layer "F.SilkS")
		)
		(fp_line
			(start 0.7874 -0.4064)
			(end 0.7874 0.4064)
			(stroke
				(width 0.1524)
				(type default)
			)
			(layer "F.SilkS")
		)
		(fp_line
			(start -0.7874 0.4064)
			(end -0.7874 -0.4064)
			(stroke
				(width 0.1524)
				(type default)
			)
			(layer "F.SilkS")
		)
		(fp_line
			(start -0.7874 -0.4064)
			(end 0.7874 -0.4064)
			(stroke
				(width 0.1524)
				(type default)
			)
			(layer "F.SilkS")
		)
		(fp_line
			(start 0.67945 0.3048)
			(end 0.120396 0.3048)
			(stroke
				(width 0.1)
				(type default)
			)
			(layer "F.Fab")
		)
		(fp_line
			(start 0.67945 -0.3048)
			(end 0.67945 0.3048)
			(stroke
				(width 0.1)
				(type default)
			)
			(layer "F.Fab")
		)
		(fp_line
			(start 0.12065 -0.2794)
			(end 0.12065 -0.3048)
			(stroke
				(width 0.1)
				(type default)
			)
			(layer "F.Fab")
		)
		(fp_line
			(start 0.12065 -0.3048)
			(end 0.67945 -0.3048)
			(stroke
				(width 0.1)
				(type default)
			)
			(layer "F.Fab")
		)
		(fp_line
			(start 0.120396 0.3048)
			(end 0.120396 0.2794)
			(stroke
				(width 0.1)
				(type default)
			)
			(layer "F.Fab")
		)
		(fp_line
			(start 0.120396 0.2794)
			(end -0.12065 0.2794)
			(stroke
				(width 0.1)
				(type default)
			)
			(layer "F.Fab")
		)
		(fp_line
			(start -0.12065 0.3048)
			(end -0.67945 0.3048)
			(stroke
				(width 0.1)
				(type default)
			)
			(layer "F.Fab")
		)
		(fp_line
			(start -0.12065 0.2794)
			(end -0.12065 0.3048)
			(stroke
				(width 0.1)
				(type default)
			)
			(layer "F.Fab")
		)
		(fp_line
			(start -0.12065 -0.2794)
			(end 0.12065 -0.2794)
			(stroke
				(width 0.1)
				(type default)
			)
			(layer "F.Fab")
		)
		(fp_line
			(start -0.12065 -0.305054)
			(end -0.12065 -0.2794)
			(stroke
				(width 0.1)
				(type default)
			)
			(layer "F.Fab")
		)
		(fp_line
			(start -0.67945 0.3048)
			(end -0.67945 -0.305054)
			(stroke
				(width 0.1)
				(type default)
			)
			(layer "F.Fab")
		)
		(fp_line
			(start -0.67945 -0.305054)
			(end -0.12065 -0.305054)
			(stroke
				(width 0.1)
				(type default)
			)
			(layer "F.Fab")
		)
		(pad "1" smd circle
			(at -0.40005 0 180)
			(size 0 0)
			(layers "F.Cu" "F.Mask" "F.Paste")
			(net "P12V_SSD9_R")
		)
		(pad "2" smd circle
			(at 0.40005 0 180)
			(size 0 0)
			(layers "F.Cu" "F.Mask" "F.Paste")
			(net "P12V_SSD9_VIN_P")
		)
	)
	(footprint ""
		(layer "F.Cu")
		(at 175.510952 -356.244906 90)
		(property "Reference" "C389"
			(at 0 0 90)
			(layer "F.SilkS")
			(hide yes)
			(effects
				(font
					(size 1.27 1.27)
				)
			)
		)
		(property "Value" ""
			(at 0 0 90)
			(layer "F.Fab")
			(effects
				(font
					(size 1.27 1.27)
				)
			)
		)
		(duplicate_pad_numbers_are_jumpers no)
		(fp_line
			(start 0.299974 -0.150114)
			(end 0.299974 0.150114)
			(stroke
				(width 0.1)
				(type default)
			)
			(layer "F.Fab")
		)
		(fp_line
			(start -0.299974 -0.150114)
			(end 0.299974 -0.150114)
			(stroke
				(width 0.1)
				(type default)
			)
			(layer "F.Fab")
		)
		(fp_line
			(start 0.299974 0.150114)
			(end -0.299974 0.150114)
			(stroke
				(width 0.1)
				(type default)
			)
			(layer "F.Fab")
		)
		(fp_line
			(start -0.299974 0.150114)
			(end -0.299974 -0.150114)
			(stroke
				(width 0.1)
				(type default)
			)
			(layer "F.Fab")
		)
		(pad "1" smd rect
			(at -0.2667 0 90)
			(size 0.3048 0.381)
			(layers "F.Cu" "F.Mask" "F.Paste")
			(net "P5E_PEX1_STN7_TX_DN<119>")
		)
		(pad "2" smd rect
			(at 0.2667 0 90)
			(size 0.3048 0.381)
			(layers "F.Cu" "F.Mask" "F.Paste")
			(net "P5E_PEX1_STN7_TX_C_DN<119>")
		)
	)
)
